# T6G (Grand Teton) — schematic netlist excerpt (pin names and nets, part order shuffled) for the footprints in the layout excerpt that follows; sources: Cadence DE-HDL packaged netlist, KiCad conversion of 04192023_DAF0TMB3IC0_F0TG_MB_C_brd_V02_OCP.brd

PR501  Q_RES  1.5 1% EMPTY  pkg 0402LF  page 196 : A = SW_PVDDCR_CPU0_P0_SW5_RC ; B = GND
PR3930  Q_RES  0 5% CHIP  pkg 0402LF  page 262 : A = AGND_HSC ; B = HSC_ADDR

(kicad_pcb
	(version 20260206)
	(generator "pcbnew")
	(generator_version "10.0")
	(general
		(thickness 1.6)
		(legacy_teardrops no)
	)
	(paper "A4")
	(title_block
		(title "04192023_DAF0TMB3IC0_F0TG_MB_C_brd_V02_OCP.brd")
		(comment 1 "Grand Teton / footprints 1083-1084 of 8354")
	)
	(layers
		(0 "F.Cu" signal "TOP")
		(4 "In1.Cu" signal "GND")
		(6 "In2.Cu" signal "IN1")
		(8 "In3.Cu" signal "GND1")
		(10 "In4.Cu" signal "IN2")
		(12 "In5.Cu" signal "GND2")
		(14 "In6.Cu" signal "IN3")
		(16 "In7.Cu" signal "GND3")
		(18 "In8.Cu" signal "VCC")
		(20 "In9.Cu" signal "VCC1")
		(22 "In10.Cu" signal "GND4")
		(24 "In11.Cu" signal "IN4")
		(26 "In12.Cu" signal "GND5")
		(28 "In13.Cu" signal "IN5")
		(30 "In14.Cu" signal "GND6")
		(32 "In15.Cu" signal "IN6")
		(34 "In16.Cu" signal "GND7")
		(2 "B.Cu" signal "BOTTOM")
		(9 "F.Adhes" user "F.Adhesive")
		(11 "B.Adhes" user "B.Adhesive")
		(13 "F.Paste" user "Package Geometry/Pastemask Top")
		(15 "B.Paste" user "Package Geometry/Pastemask Bottom")
		(5 "F.SilkS" user "Ref Des/Silkscreen Top")
		(7 "B.SilkS" user "Ref Des/Silkscreen Bottom")
		(1 "F.Mask" user "Board Geometry/Soldermask Top")
		(3 "B.Mask" user "Board Geometry/Soldermask Bottom")
		(17 "Dwgs.User" user "User.Drawings")
		(19 "Cmts.User" user "User.Comments")
		(21 "Eco1.User" user "User.Eco1")
		(23 "Eco2.User" user "User.Eco2")
		(25 "Edge.Cuts" user "Board Geometry/Outline")
		(27 "Margin" user)
		(31 "F.CrtYd" user "Package Geometry/Place Bound Top")
		(29 "B.CrtYd" user "Package Geometry/Place Bound Bottom")
		(35 "F.Fab" user "Ref Des/Assembly Top")
		(33 "B.Fab" user "Ref Des/Assembly Bottom")
	)
	(footprint ""
		(layer "F.Cu")
		(at 359.710736 -171.23029 -90)
		(property "Reference" "PR501"
			(at 0 0 270)
			(layer "F.SilkS")
			(hide yes)
			(effects
				(font
					(size 1.27 1.27)
				)
			)
		)
		(property "Value" ""
			(at 0 0 270)
			(layer "F.Fab")
			(effects
				(font
					(size 1.27 1.27)
				)
			)
		)
		(duplicate_pad_numbers_are_jumpers no)
		(fp_line
			(start -0.7874 0.4064)
			(end -0.7874 -0.4064)
			(stroke
				(width 0.1524)
				(type default)
			)
			(layer "F.SilkS")
		)
		(fp_line
			(start 0.7874 0.4064)
			(end -0.7874 0.4064)
			(stroke
				(width 0.1524)
				(type default)
			)
			(layer "F.SilkS")
		)
		(fp_line
			(start -0.7874 -0.4064)
			(end 0.7874 -0.4064)
			(stroke
				(width 0.1524)
				(type default)
			)
			(layer "F.SilkS")
		)
		(fp_line
			(start 0.7874 -0.4064)
			(end 0.7874 0.4064)
			(stroke
				(width 0.1524)
				(type default)
			)
			(layer "F.SilkS")
		)
		(fp_line
			(start -0.67945 0.3048)
			(end -0.67945 -0.305054)
			(stroke
				(width 0.1)
				(type default)
			)
			(layer "F.Fab")
		)
		(fp_line
			(start -0.12065 0.3048)
			(end -0.67945 0.3048)
			(stroke
				(width 0.1)
				(type default)
			)
			(layer "F.Fab")
		)
		(fp_line
			(start 0.120396 0.3048)
			(end 0.120396 0.2794)
			(stroke
				(width 0.1)
				(type default)
			)
			(layer "F.Fab")
		)
		(fp_line
			(start 0.67945 0.3048)
			(end 0.120396 0.3048)
			(stroke
				(width 0.1)
				(type default)
			)
			(layer "F.Fab")
		)
		(fp_line
			(start -0.12065 0.2794)
			(end -0.12065 0.3048)
			(stroke
				(width 0.1)
				(type default)
			)
			(layer "F.Fab")
		)
		(fp_line
			(start 0.120396 0.2794)
			(end -0.12065 0.2794)
			(stroke
				(width 0.1)
				(type default)
			)
			(layer "F.Fab")
		)
		(fp_line
			(start -0.12065 -0.2794)
			(end 0.12065 -0.2794)
			(stroke
				(width 0.1)
				(type default)
			)
			(layer "F.Fab")
		)
		(fp_line
			(start 0.12065 -0.2794)
			(end 0.12065 -0.3048)
			(stroke
				(width 0.1)
				(type default)
			)
			(layer "F.Fab")
		)
		(fp_line
			(start 0.12065 -0.3048)
			(end 0.67945 -0.3048)
			(stroke
				(width 0.1)
				(type default)
			)
			(layer "F.Fab")
		)
		(fp_line
			(start 0.67945 -0.3048)
			(end 0.67945 0.3048)
			(stroke
				(width 0.1)
				(type default)
			)
			(layer "F.Fab")
		)
		(fp_line
			(start -0.67945 -0.305054)
			(end -0.12065 -0.305054)
			(stroke
				(width 0.1)
				(type default)
			)
			(layer "F.Fab")
		)
		(fp_line
			(start -0.12065 -0.305054)
			(end -0.12065 -0.2794)
			(stroke
				(width 0.1)
				(type default)
			)
			(layer "F.Fab")
		)
		(pad "1" smd circle
			(at -0.40005 0 270)
			(size 0 0)
			(layers "F.Cu" "F.Mask" "F.Paste")
			(net "SW_PVDDCR_CPU0_P0_SW5_RC")
		)
		(pad "2" smd circle
			(at 0.40005 0 270)
			(size 0 0)
			(layers "F.Cu" "F.Mask" "F.Paste")
			(net "GND")
		)
	)
	(footprint ""
		(layer "F.Cu")
		(at 178.72456 -396.385542)
		(property "Reference" "PR3930"
			(at 0 0 0)
			(layer "F.SilkS")
			(hide yes)
			(effects
				(font
					(size 1.27 1.27)
				)
			)
		)
		(property "Value" ""
			(at 0 0 0)
			(layer "F.Fab")
			(effects
				(font
					(size 1.27 1.27)
				)
			)
		)
		(duplicate_pad_numbers_are_jumpers no)
		(fp_line
			(start -0.7874 -0.4064)
			(end 0.7874 -0.4064)
			(stroke
				(width 0.1524)
				(type default)
			)
			(layer "F.SilkS")
		)
		(fp_line
			(start -0.7874 0.4064)
			(end -0.7874 -0.4064)
			(stroke
				(width 0.1524)
				(type default)
			)
			(layer "F.SilkS")
		)
		(fp_line
			(start 0.7874 -0.4064)
			(end 0.7874 0.4064)
			(stroke
				(width 0.1524)
				(type default)
			)
			(layer "F.SilkS")
		)
		(fp_line
			(start 0.7874 0.4064)
			(end -0.7874 0.4064)
			(stroke
				(width 0.1524)
				(type default)
			)
			(layer "F.SilkS")
		)
		(fp_line
			(start -0.67945 -0.305054)
			(end -0.12065 -0.305054)
			(stroke
				(width 0.1)
				(type default)
			)
			(layer "F.Fab")
		)
		(fp_line
			(start -0.67945 0.3048)
			(end -0.67945 -0.305054)
			(stroke
				(width 0.1)
				(type default)
			)
			(layer "F.Fab")
		)
		(fp_line
			(start -0.12065 -0.305054)
			(end -0.12065 -0.2794)
			(stroke
				(width 0.1)
				(type default)
			)
			(layer "F.Fab")
		)
		(fp_line
			(start -0.12065 -0.2794)
			(end 0.12065 -0.2794)
			(stroke
				(width 0.1)
				(type default)
			)
			(layer "F.Fab")
		)
		(fp_line
			(start -0.12065 0.2794)
			(end -0.12065 0.3048)
			(stroke
				(width 0.1)
				(type default)
			)
			(layer "F.Fab")
		)
		(fp_line
			(start -0.12065 0.3048)
			(end -0.67945 0.3048)
			(stroke
				(width 0.1)
				(type default)
			)
			(layer "F.Fab")
		)
		(fp_line
			(start 0.120396 0.2794)
			(end -0.12065 0.2794)
			(stroke
				(width 0.1)
				(type default)
			)
			(layer "F.Fab")
		)
		(fp_line
			(start 0.120396 0.3048)
			(end 0.120396 0.2794)
			(stroke
				(width 0.1)
				(type default)
			)
			(layer "F.Fab")
		)
		(fp_line
			(start 0.12065 -0.3048)
			(end 0.67945 -0.3048)
			(stroke
				(width 0.1)
				(type default)
			)
			(layer "F.Fab")
		)
		(fp_line
			(start 0.12065 -0.2794)
			(end 0.12065 -0.3048)
			(stroke
				(width 0.1)
				(type default)
			)
			(layer "F.Fab")
		)
		(fp_line
			(start 0.67945 -0.3048)
			(end 0.67945 0.3048)
			(stroke
				(width 0.1)
				(type default)
			)
			(layer "F.Fab")
		)
		(fp_line
			(start 0.67945 0.3048)
			(end 0.120396 0.3048)
			(stroke
				(width 0.1)
				(type default)
			)
			(layer "F.Fab")
		)
		(pad "1" smd circle
			(at -0.40005 0)
			(size 0 0)
			(layers "F.Cu" "F.Mask" "F.Paste")
			(net "AGND_HSC")
		)
		(pad "2" smd circle
			(at 0.40005 0)
			(size 0 0)
			(layers "F.Cu" "F.Mask" "F.Paste")
			(net "HSC_ADDR")
		)
	)
)
